(kicad_pcb
	(version 20241229)
	(generator "pcbnew")
	(generator_version "9.0")
	(general
		(thickness 1.62)
		(legacy_teardrops no)
	)
	(paper "A4")
	(title_block
		(title "OCuLink to 10GbE adapter")
		(date "2026-02-23")
		(rev "1.1.0")
		(company "Antmicro Ltd")
		(comment 1 "www.antmicro.com")
		(comment 9 "footprints 130-135 of 510")
	)
	(layers
		(0 "F.Cu" signal)
		(4 "In1.Cu" signal)
		(6 "In2.Cu" signal)
		(8 "In3.Cu" signal)
		(10 "In4.Cu" signal)
		(12 "In5.Cu" signal)
		(14 "In6.Cu" signal)
		(2 "B.Cu" signal)
		(9 "F.Adhes" user "F.Adhesive")
		(11 "B.Adhes" user "B.Adhesive")
		(13 "F.Paste" user)
		(15 "B.Paste" user)
		(5 "F.SilkS" user "F.Silkscreen")
		(7 "B.SilkS" user "B.Silkscreen")
		(1 "F.Mask" user)
		(3 "B.Mask" user)
		(17 "Dwgs.User" user "User.Drawings")
		(19 "Cmts.User" user "User.Comments")
		(21 "Eco1.User" user "User.Eco1")
		(23 "Eco2.User" user "User.Eco2")
		(25 "Edge.Cuts" user)
		(27 "Margin" user)
		(31 "F.CrtYd" user "F.Courtyard")
		(29 "B.CrtYd" user "B.Courtyard")
		(35 "F.Fab" user)
		(33 "B.Fab" user)
	)
	(footprint "antmicro-footprints:R_0402_1005Metric"
		(layer "F.Cu")
		(at 56.100001 85.149999 90)
		(descr "Resistor SMD 0402")
		(tags "resistor SMD 0402")
		(property "Reference" "R9"
			(at -1.650001 -0.750001 180)
			(layer "F.SilkS")
			(effects
				(font
					(size 0.7 0.7)
					(thickness 0.15)
				)
				(justify left bottom)
			)
		)
		(property "Value" "R_16k_0402"
			(at -1.011843 1.772046 90)
			(layer "F.Fab")
			(hide yes)
			(effects
				(font
					(size 0.7 0.7)
					(thickness 0.15)
				)
				(justify left bottom)
			)
		)
		(property "Datasheet" "https://www.bourns.com/docs/product-datasheets/cr.pdf"
			(at 0 0 90)
			(layer "F.Fab")
			(hide yes)
			(effects
				(font
					(size 1.27 1.27)
					(thickness 0.15)
				)
			)
		)
		(property "Description" "SMD Chip Resistor"
			(at 0 0 90)
			(layer "F.Fab")
			(hide yes)
			(effects
				(font
					(size 1.27 1.27)
					(thickness 0.15)
				)
			)
		)
		(property "MPN" "CR0402-FX-1602GLF"
			(at 0 0 90)
			(unlocked yes)
			(layer "F.Fab")
			(hide yes)
			(effects
				(font
					(size 1 1)
					(thickness 0.15)
				)
			)
		)
		(property "Manufacturer" "Bourns"
			(at 0 0 90)
			(unlocked yes)
			(layer "F.Fab")
			(hide yes)
			(effects
				(font
					(size 1 1)
					(thickness 0.15)
				)
			)
		)
		(property "License" "Apache-2.0"
			(at 0 0 90)
			(unlocked yes)
			(layer "F.Fab")
			(hide yes)
			(effects
				(font
					(size 1 1)
					(thickness 0.15)
				)
			)
		)
		(property "Author" "Antmicro"
			(at 0 0 90)
			(unlocked yes)
			(layer "F.Fab")
			(hide yes)
			(effects
				(font
					(size 1 1)
					(thickness 0.15)
				)
			)
		)
		(property "Val" "16k"
			(at 0 0 90)
			(unlocked yes)
			(layer "F.Fab")
			(hide yes)
			(effects
				(font
					(size 1 1)
					(thickness 0.15)
				)
			)
		)
		(property "Tolerance" "1%"
			(at 0 0 90)
			(unlocked yes)
			(layer "F.Fab")
			(hide yes)
			(effects
				(font
					(size 1 1)
					(thickness 0.15)
				)
			)
		)
		(sheetname "/Power/")
		(sheetfile "power.kicad_sch")
		(attr smd)
		(fp_rect
			(start -0.925 -0.47)
			(end 0.925 0.47)
			(stroke
				(width 0.05)
				(type default)
			)
			(fill no)
			(layer "F.CrtYd")
		)
		(fp_rect
			(start -0.5 -0.25)
			(end 0.5 0.25)
			(stroke
				(width 0.15)
				(type solid)
			)
			(fill no)
			(layer "F.Fab")
		)
		(pad "1" smd roundrect
			(at -0.48 0 90)
			(size 0.59 0.64)
			(layers "F.Cu" "F.Mask" "F.Paste")
			(roundrect_rratio 0.25)
			(net 329 "/Power/VCCD_FB")
			(pintype "passive")
		)
		(pad "2" smd roundrect
			(at 0.48 0 90)
			(size 0.59 0.64)
			(layers "F.Cu" "F.Mask" "F.Paste")
			(roundrect_rratio 0.25)
			(net 303 "/Power/+VCCD_OUT")
			(pintype "passive")
		)
	)
	(footprint "antmicro-footprints:R_0402_1005Metric"
		(layer "F.Cu")
		(at 89.1 112.45 -90)
		(descr "Resistor SMD 0402")
		(tags "resistor SMD 0402")
		(property "Reference" "R73"
			(at 0.85 -0.4625 90)
			(layer "F.SilkS")
			(effects
				(font
					(size 0.7 0.7)
					(thickness 0.15)
				)
				(justify right bottom)
			)
		)
		(property "Value" "R_1k_0402"
			(at -1.011843 1.772046 90)
			(layer "F.Fab")
			(hide yes)
			(effects
				(font
					(size 0.7 0.7)
					(thickness 0.15)
				)
				(justify right top)
			)
		)
		(property "Datasheet" "https://www.bourns.com/docs/product-datasheets/cr.pdf"
			(at 0 0 90)
			(layer "F.Fab")
			(hide yes)
			(effects
				(font
					(size 1.27 1.27)
					(thickness 0.15)
				)
			)
		)
		(property "Description" "SMD Chip Resistor, 1 kohm, ± 1%, 63 mW, 0402 [1005 Metric], Thick Film, General Purpose"
			(at 0 0 90)
			(layer "F.Fab")
			(hide yes)
			(effects
				(font
					(size 1.27 1.27)
					(thickness 0.15)
				)
			)
		)
		(property "MPN" "CR0402-FX-1001GLF"
			(at 0 0 270)
			(unlocked yes)
			(layer "F.Fab")
			(hide yes)
			(effects
				(font
					(size 1 1)
					(thickness 0.15)
				)
			)
		)
		(property "Manufacturer" "Bourns"
			(at 0 0 270)
			(unlocked yes)
			(layer "F.Fab")
			(hide yes)
			(effects
				(font
					(size 1 1)
					(thickness 0.15)
				)
			)
		)
		(property "License" "Apache-2.0"
			(at 0 0 270)
			(unlocked yes)
			(layer "F.Fab")
			(hide yes)
			(effects
				(font
					(size 1 1)
					(thickness 0.15)
				)
			)
		)
		(property "Author" "Antmicro"
			(at 0 0 270)
			(unlocked yes)
			(layer "F.Fab")
			(hide yes)
			(effects
				(font
					(size 1 1)
					(thickness 0.15)
				)
			)
		)
		(property "Val" "1k"
			(at 0 0 270)
			(unlocked yes)
			(layer "F.Fab")
			(hide yes)
			(effects
				(font
					(size 1 1)
					(thickness 0.15)
				)
			)
		)
		(property "Tolerance" "1%"
			(at 0 0 270)
			(unlocked yes)
			(layer "F.Fab")
			(hide yes)
			(effects
				(font
					(size 1 1)
					(thickness 0.15)
				)
			)
		)
		(sheetname "/X710-AT2 10GbE/")
		(sheetfile "x710-at2-10gbe.kicad_sch")
		(attr smd exclude_from_pos_files exclude_from_bom dnp)
		(fp_rect
			(start -0.925 -0.47)
			(end 0.925 0.47)
			(stroke
				(width 0.05)
				(type default)
			)
			(fill no)
			(layer "F.CrtYd")
		)
		(fp_rect
			(start -0.5 -0.25)
			(end 0.5 0.25)
			(stroke
				(width 0.15)
				(type solid)
			)
			(fill no)
			(layer "F.Fab")
		)
		(pad "1" smd roundrect
			(at -0.48 0 270)
			(size 0.59 0.64)
			(layers "F.Cu" "F.Mask" "F.Paste")
			(roundrect_rratio 0.25)
			(net 294 "/X710-AT2 10GbE/TPIN_5")
			(pintype "passive")
		)
		(pad "2" smd roundrect
			(at 0.48 0 270)
			(size 0.59 0.64)
			(layers "F.Cu" "F.Mask" "F.Paste")
			(roundrect_rratio 0.25)
			(net 18 "+1V88")
			(pintype "passive")
		)
	)
	(footprint "antmicro-footprints:Conn_Molex_KK_1x4_0470531000"
		(layer "F.Cu")
		(at 115.4 117.44 90)
		(property "Reference" "J8"
			(at 5.18 -3 90)
			(layer "F.SilkS")
			(effects
				(font
					(size 0.7 0.7)
					(thickness 0.15)
				)
				(justify left bottom)
			)
		)
		(property "Value" "Molex_KK_1x4_0470531000"
			(at 0 4.7 90)
			(layer "F.Fab")
			(hide yes)
			(effects
				(font
					(size 0.7 0.7)
					(thickness 0.15)
				)
				(justify left bottom)
			)
		)
		(property "Datasheet" "https://tools.molex.com/pdm_docs/sd/470531000_sd.pdf"
			(at 0 0 90)
			(layer "F.Fab")
			(hide yes)
			(effects
				(font
					(size 1.27 1.27)
					(thickness 0.15)
				)
			)
		)
		(property "Description" "Connector Header, THT,  4x1"
			(at 0 0 90)
			(layer "F.Fab")
			(hide yes)
			(effects
				(font
					(size 1.27 1.27)
					(thickness 0.15)
				)
			)
		)
		(property "MPN" "0470531000"
			(at 0 0 90)
			(unlocked yes)
			(layer "F.Fab")
			(hide yes)
			(effects
				(font
					(size 1 1)
					(thickness 0.15)
				)
			)
		)
		(property "Manufacturer" "Molex"
			(at 0 0 90)
			(unlocked yes)
			(layer "F.Fab")
			(hide yes)
			(effects
				(font
					(size 1 1)
					(thickness 0.15)
				)
			)
		)
		(property "Author" "Antmicro"
			(at 0 0 90)
			(unlocked yes)
			(layer "F.Fab")
			(hide yes)
			(effects
				(font
					(size 1 1)
					(thickness 0.15)
				)
			)
		)
		(property "License" "Apache-2.0"
			(at 0 0 90)
			(unlocked yes)
			(layer "F.Fab")
			(hide yes)
			(effects
				(font
					(size 1 1)
					(thickness 0.15)
				)
			)
		)
		(sheetname "/Fan controller/")
		(sheetfile "fan-controller.kicad_sch")
		(attr through_hole exclude_from_pos_files exclude_from_bom dnp)
		(fp_line
			(start -1.35 -2.6)
			(end 4.4 -2.6)
			(stroke
				(width 0.15)
				(type solid)
			)
			(layer "F.SilkS")
		)
		(fp_line
			(start 8.95 -2.55)
			(end 8.95 3.4)
			(stroke
				(width 0.15)
				(type solid)
			)
			(layer "F.SilkS")
		)
		(fp_line
			(start 5.75 -2.55)
			(end 8.95 -2.55)
			(stroke
				(width 0.15)
				(type solid)
			)
			(layer "F.SilkS")
		)
		(fp_line
			(start 5.08 2.29)
			(end 5.08 3.3)
			(stroke
				(width 0.15)
				(type solid)
			)
			(layer "F.SilkS")
		)
		(fp_line
			(start 0 2.29)
			(end 5.08 2.29)
			(stroke
				(width 0.15)
				(type solid)
			)
			(layer "F.SilkS")
		)
		(fp_line
			(start 0 3.3)
			(end 0 2.29)
			(stroke
				(width 0.15)
				(type solid)
			)
			(layer "F.SilkS")
		)
		(fp_line
			(start 8.95 3.4)
			(end -1.35 3.4)
			(stroke
				(width 0.15)
				(type solid)
			)
			(layer "F.SilkS")
		)
		(fp_line
			(start -1.35 3.4)
			(end -1.35 -2.6)
			(stroke
				(width 0.15)
				(type solid)
			)
			(layer "F.SilkS")
		)
		(fp_circle
			(center 0 -3)
			(end 0.05 -3)
			(stroke
				(width 0.15)
				(type solid)
			)
			(fill yes)
			(layer "F.SilkS")
		)
		(fp_rect
			(start -1.54 -2.96)
			(end 9.16 3.55)
			(stroke
				(width 0.05)
				(type solid)
			)
			(fill no)
			(layer "F.CrtYd")
		)
		(fp_line
			(start 8.85 -2.5)
			(end 8.85 3.3)
			(stroke
				(width 0.15)
				(type solid)
			)
			(layer "F.Fab")
		)
		(fp_line
			(start 5.75 -2.5)
			(end 8.85 -2.5)
			(stroke
				(width 0.15)
				(type solid)
			)
			(layer "F.Fab")
		)
		(fp_line
			(start -1.25 -2.5)
			(end 4.4 -2.5)
			(stroke
				(width 0.15)
				(type solid)
			)
			(layer "F.Fab")
		)
		(fp_line
			(start 5.1 2.3)
			(end 0 2.3)
			(stroke
				(width 0.15)
				(type solid)
			)
			(layer "F.Fab")
		)
		(fp_line
			(start 0 2.3)
			(end 0 3.3)
			(stroke
				(width 0.15)
				(type solid)
			)
			(layer "F.Fab")
		)
		(fp_line
			(start 8.85 3.3)
			(end -1.2 3.3)
			(stroke
				(width 0.15)
				(type solid)
			)
			(layer "F.Fab")
		)
		(fp_line
			(start 5.1 3.3)
			(end 5.1 2.3)
			(stroke
				(width 0.15)
				(type solid)
			)
			(layer "F.Fab")
		)
		(fp_line
			(start -1.2 3.3)
			(end -1.25 3.3)
			(stroke
				(width 0.15)
				(type solid)
			)
			(layer "F.Fab")
		)
		(fp_line
			(start -1.25 3.3)
			(end -1.25 -2.5)
			(stroke
				(width 0.15)
				(type solid)
			)
			(layer "F.Fab")
		)
		(pad "" np_thru_hole circle
			(at 5.08 -2.16 180)
			(size 1.1 1.1)
			(drill 1.1)
			(layers "*.Cu" "*.Mask")
		)
		(pad "1" thru_hole rect
			(at 0 0 180)
			(size 2.03 1.73)
			(drill 1.02)
			(layers "*.Cu" "*.Mask")
			(remove_unused_layers no)
			(net 28 "GND")
			(pintype "passive")
		)
		(pad "2" thru_hole oval
			(at 2.54 0 180)
			(size 2.03 1.73)
			(drill 1.02)
			(layers "*.Cu" "*.Mask")
			(remove_unused_layers no)
			(net 389 "/Fan controller/V_{FAN}")
			(pintype "passive")
		)
		(pad "3" thru_hole oval
			(at 5.08 0 180)
			(size 2.03 1.73)
			(drill 1.02)
			(layers "*.Cu" "*.Mask")
			(remove_unused_layers no)
			(net 391 "/Fan controller/TACH")
			(pintype "passive+no_connect")
		)
		(pad "4" thru_hole oval
			(at 7.62 0 180)
			(size 2.03 1.73)
			(drill 1.02)
			(layers "*.Cu" "*.Mask")
			(remove_unused_layers no)
			(net 390 "/Fan controller/PWM")
			(pintype "passive")
		)
	)
	(footprint "antmicro-footprints:R_0402_1005Metric"
		(layer "F.Cu")
		(at 112.15 100.1 90)
		(descr "Resistor SMD 0402")
		(tags "resistor SMD 0402")
		(property "Reference" "R179"
			(at 0.8 -1.55 90)
			(layer "F.SilkS")
			(effects
				(font
					(size 0.7 0.7)
					(thickness 0.15)
				)
				(justify left bottom)
			)
		)
		(property "Value" "R_10k_0402"
			(at -1.011843 1.772046 90)
			(layer "F.Fab")
			(hide yes)
			(effects
				(font
					(size 0.7 0.7)
					(thickness 0.15)
				)
				(justify left bottom)
			)
		)
		(property "Datasheet" "https://www.bourns.com/docs/product-datasheets/cr.pdf"
			(at 0 0 90)
			(layer "F.Fab")
			(hide yes)
			(effects
				(font
					(size 1.27 1.27)
					(thickness 0.15)
				)
			)
		)
		(property "Description" "SMD Chip Resistor, 10 kohm, ± 1%, 62.5 mW, 0402 [1005 Metric], Thick Film, General Purpose"
			(at 0 0 90)
			(layer "F.Fab")
			(hide yes)
			(effects
				(font
					(size 1.27 1.27)
					(thickness 0.15)
				)
			)
		)
		(property "MPN" "CR0402-FX-1002GLF"
			(at 0 0 90)
			(unlocked yes)
			(layer "F.Fab")
			(hide yes)
			(effects
				(font
					(size 1 1)
					(thickness 0.15)
				)
			)
		)
		(property "Manufacturer" "Bourns"
			(at 0 0 90)
			(unlocked yes)
			(layer "F.Fab")
			(hide yes)
			(effects
				(font
					(size 1 1)
					(thickness 0.15)
				)
			)
		)
		(property "License" "Apache-2.0"
			(at 0 0 90)
			(unlocked yes)
			(layer "F.Fab")
			(hide yes)
			(effects
				(font
					(size 1 1)
					(thickness 0.15)
				)
			)
		)
		(property "Author" "Antmicro"
			(at 0 0 90)
			(unlocked yes)
			(layer "F.Fab")
			(hide yes)
			(effects
				(font
					(size 1 1)
					(thickness 0.15)
				)
			)
		)
		(property "Val" "10k"
			(at 0 0 90)
			(unlocked yes)
			(layer "F.Fab")
			(hide yes)
			(effects
				(font
					(size 1 1)
					(thickness 0.15)
				)
			)
		)
		(property "Tolerance" "1%"
			(at 0 0 90)
			(unlocked yes)
			(layer "F.Fab")
			(hide yes)
			(effects
				(font
					(size 1 1)
					(thickness 0.15)
				)
			)
		)
		(sheetname "/Fan controller/")
		(sheetfile "fan-controller.kicad_sch")
		(attr smd exclude_from_pos_files exclude_from_bom dnp)
		(fp_rect
			(start -0.925 -0.47)
			(end 0.925 0.47)
			(stroke
				(width 0.05)
				(type default)
			)
			(fill no)
			(layer "F.CrtYd")
		)
		(fp_rect
			(start -0.5 -0.25)
			(end 0.5 0.25)
			(stroke
				(width 0.15)
				(type solid)
			)
			(fill no)
			(layer "F.Fab")
		)
		(pad "1" smd roundrect
			(at -0.48 0 90)
			(size 0.59 0.64)
			(layers "F.Cu" "F.Mask" "F.Paste")
			(roundrect_rratio 0.25)
			(net 399 "/Fan controller/DMIN")
			(pintype "passive")
		)
		(pad "2" smd roundrect
			(at 0.48 0 90)
			(size 0.59 0.64)
			(layers "F.Cu" "F.Mask" "F.Paste")
			(roundrect_rratio 0.25)
			(net 388 "/Fan controller/+5V")
			(pintype "passive")
		)
	)
	(footprint "antmicro-footprints:R_0402_1005Metric"
		(layer "F.Cu")
		(at 99.349999 110.1 180)
		(descr "Resistor SMD 0402")
		(tags "resistor SMD 0402")
		(property "Reference" "R46"
			(at 1.249999 -15.75 0)
			(layer "F.SilkS")
			(effects
				(font
					(size 0.7 0.7)
					(thickness 0.15)
				)
				(justify left bottom)
			)
		)
		(property "Value" "R_150R_0402"
			(at -1.011843 1.772046 0)
			(layer "F.Fab")
			(hide yes)
			(effects
				(font
					(size 0.7 0.7)
					(thickness 0.15)
				)
				(justify right top)
			)
		)
		(property "Datasheet" "https://www.bourns.com/docs/product-datasheets/cr.pdf"
			(at 0 0 0)
			(layer "F.Fab")
			(hide yes)
			(effects
				(font
					(size 1.27 1.27)
					(thickness 0.15)
				)
			)
		)
		(property "Description" "SMD Chip Resistor, 150 ohm, ± 1%, 62.5 mW, 0402 [1005 Metric], Thick Film, General Purpose"
			(at 0 0 0)
			(layer "F.Fab")
			(hide yes)
			(effects
				(font
					(size 1.27 1.27)
					(thickness 0.15)
				)
			)
		)
		(property "MPN" "CR0402-FX-1500GLF"
			(at 0 0 180)
			(unlocked yes)
			(layer "F.Fab")
			(hide yes)
			(effects
				(font
					(size 1 1)
					(thickness 0.15)
				)
			)
		)
		(property "Manufacturer" "Bourns"
			(at 0 0 180)
			(unlocked yes)
			(layer "F.Fab")
			(hide yes)
			(effects
				(font
					(size 1 1)
					(thickness 0.15)
				)
			)
		)
		(property "License" "Apache-2.0"
			(at 0 0 180)
			(unlocked yes)
			(layer "F.Fab")
			(hide yes)
			(effects
				(font
					(size 1 1)
					(thickness 0.15)
				)
			)
		)
		(property "Author" "Antmicro"
			(at 0 0 180)
			(unlocked yes)
			(layer "F.Fab")
			(hide yes)
			(effects
				(font
					(size 1 1)
					(thickness 0.15)
				)
			)
		)
		(property "Val" "150R"
			(at 0 0 180)
			(unlocked yes)
			(layer "F.Fab")
			(hide yes)
			(effects
				(font
					(size 1 1)
					(thickness 0.15)
				)
			)
		)
		(property "Tolerance" "1%"
			(at 0 0 180)
			(unlocked yes)
			(layer "F.Fab")
			(hide yes)
			(effects
				(font
					(size 1 1)
					(thickness 0.15)
				)
			)
		)
		(sheetname "/X710-AT2 10GbE/")
		(sheetfile "x710-at2-10gbe.kicad_sch")
		(attr smd)
		(fp_rect
			(start -0.925 -0.47)
			(end 0.925 0.47)
			(stroke
				(width 0.05)
				(type default)
			)
			(fill no)
			(layer "F.CrtYd")
		)
		(fp_rect
			(start -0.5 -0.25)
			(end 0.5 0.25)
			(stroke
				(width 0.15)
				(type solid)
			)
			(fill no)
			(layer "F.Fab")
		)
		(pad "1" smd roundrect
			(at -0.48 0 180)
			(size 0.59 0.64)
			(layers "F.Cu" "F.Mask" "F.Paste")
			(roundrect_rratio 0.25)
			(net 28 "GND")
			(pintype "passive")
		)
		(pad "2" smd roundrect
			(at 0.48 0 180)
			(size 0.59 0.64)
			(layers "F.Cu" "F.Mask" "F.Paste")
			(roundrect_rratio 0.25)
			(net 73 "/X710-AT2 10GbE/25MHZ_OSC_AC.-")
			(pintype "passive")
		)
	)
	(footprint "antmicro-footprints:R_0402_1005Metric"
		(layer "F.Cu")
		(at 71.8 91.305 90)
		(descr "Resistor SMD 0402")
		(tags "resistor SMD 0402")
		(property "Reference" "R94"
			(at 0.785 0.34 90)
			(layer "F.SilkS")
			(effects
				(font
					(size 0.7 0.7)
					(thickness 0.15)
				)
				(justify left bottom)
			)
		)
		(property "Value" "R_10k_0402"
			(at -1.011843 1.772046 90)
			(layer "F.Fab")
			(hide yes)
			(effects
				(font
					(size 0.7 0.7)
					(thickness 0.15)
				)
				(justify left bottom)
			)
		)
		(property "Datasheet" "https://www.bourns.com/docs/product-datasheets/cr.pdf"
			(at 0 0 90)
			(layer "F.Fab")
			(hide yes)
			(effects
				(font
					(size 1.27 1.27)
					(thickness 0.15)
				)
			)
		)
		(property "Description" "SMD Chip Resistor, 10 kohm, ± 1%, 62.5 mW, 0402 [1005 Metric], Thick Film, General Purpose"
			(at 0 0 90)
			(layer "F.Fab")
			(hide yes)
			(effects
				(font
					(size 1.27 1.27)
					(thickness 0.15)
				)
			)
		)
		(property "MPN" "CR0402-FX-1002GLF"
			(at 0 0 90)
			(unlocked yes)
			(layer "F.Fab")
			(hide yes)
			(effects
				(font
					(size 1 1)
					(thickness 0.15)
				)
			)
		)
		(property "Manufacturer" "Bourns"
			(at 0 0 90)
			(unlocked yes)
			(layer "F.Fab")
			(hide yes)
			(effects
				(font
					(size 1 1)
					(thickness 0.15)
				)
			)
		)
		(property "License" "Apache-2.0"
			(at 0 0 90)
			(unlocked yes)
			(layer "F.Fab")
			(hide yes)
			(effects
				(font
					(size 1 1)
					(thickness 0.15)
				)
			)
		)
		(property "Author" "Antmicro"
			(at 0 0 90)
			(unlocked yes)
			(layer "F.Fab")
			(hide yes)
			(effects
				(font
					(size 1 1)
					(thickness 0.15)
				)
			)
		)
		(property "Val" "10k"
			(at 0 0 90)
			(unlocked yes)
			(layer "F.Fab")
			(hide yes)
			(effects
				(font
					(size 1 1)
					(thickness 0.15)
				)
			)
		)
		(property "Tolerance" "1%"
			(at 0 0 90)
			(unlocked yes)
			(layer "F.Fab")
			(hide yes)
			(effects
				(font
					(size 1 1)
					(thickness 0.15)
				)
			)
		)
		(sheetname "/X710-AT2 Misc/")
		(sheetfile "x710-at2-mics.kicad_sch")
		(attr smd)
		(fp_rect
			(start -0.925 -0.47)
			(end 0.925 0.47)
			(stroke
				(width 0.05)
				(type default)
			)
			(fill no)
			(layer "F.CrtYd")
		)
		(fp_rect
			(start -0.5 -0.25)
			(end 0.5 0.25)
			(stroke
				(width 0.15)
				(type solid)
			)
			(fill no)
			(layer "F.Fab")
		)
		(pad "1" smd roundrect
			(at -0.48 0 90)
			(size 0.59 0.64)
			(layers "F.Cu" "F.Mask" "F.Paste")
			(roundrect_rratio 0.25)
			(net 105 "/Flash memory/FLASH.~{CE}")
			(pintype "passive")
		)
		(pad "2" smd roundrect
			(at 0.48 0 90)
			(size 0.59 0.64)
			(layers "F.Cu" "F.Mask" "F.Paste")
			(roundrect_rratio 0.25)
			(net 7 "+3V3")
			(pintype "passive")
		)
	)
)
